# Primary and Alternate BOM of B91.01110.0018_Front panel.xls — Sheet0 (bom)
| Part Number | B91.01110.0018 |  |  |  |  |  |  |  |  |  |  |  |  |
| Revision | B |  |  |  |  |  |  |  |  |  |  |  |  |
| Sequence | 1 |  |  |  |  |  |  |  |  |  |  |  |  |
| Description | BRYCE CANYON FRONT PANEL GCE-1 P MAIN |  |  |  |  |  |  |  |  |  |  |  |  |
| Project Code | BPD011010001 |  |  |  |  |  |  |  |  |  |  |  |  |
| Latest Revision? | YES |  |  |  |  |  |  |  |  |  |  |  |  |
| PDM BOM List |  |  |  |  |  |  |  |  |  |  |  |  |  |
| Level | Parent Number | Part Number | Description | Green Factor | Manufacturer | Manufacturer Part Number | Source | BOM Usage | M/P Code | S/D | Qty | UoM | Location |
| 1 | B91.01110.0018 | B55.01109.0002 | BRYCE CANYON FRONT PANEL GCE-1 P MAIN(D) | R2; |  |  |  | M | Manufacture |  | 1 | PCS |  |
| 2 | B55.01109.0002 | 006.03870.0140 | LED YELLOW LA38B-70/VY-1-PF | R2_SA;HF_SA; | LIGITEK | LA38B-70/VY-1-PF | Single |  | Purchase | DIP | 2 | PCS | LED1 LED2 |
| 2 | B55.01109.0002 | 022.10005.0D41 | SKT USB3.0 9P GSB312137CHR DIP ,PA4T | R2_SA;HF_SA; | AMPHENOL | GSB312137CHR | Single |  | Purchase | DIP | 2 | PCS | USB1 USB2 |
| 2 | B55.01109.0002 | 022.40001.00B1 | SW TACT 6P PS004-L22NPR1KKK3UBXX | R2_SA;HF_SA; | WELLBUY | PS004-L22NPR1KKK3UBXX | Single |  | Purchase | DIP | 2 | PCS | SW1 SW2 |
| 2 | B55.01109.0002 | 40.58D03.001 | LBL POLYIMIDE31.8*6.35 BARCODE | R2_SA;HF_SA;G_SA; | LABELJET | 40.58D03.001 | Single |  | Purchase | DIP | 1 | PCS |  |
| 2 | B55.01109.0002 | 640.00X01.0001 | LBL 7X7MM  FOR SONIC | R2_SA;HF_SA; | WISTRON | 640.00X01.0001 | Single |  | Purchase | DIP | 1 | PCS |  |
| 2 | B55.01109.0002 | B55.01109.M002 | BRYCE CANYON FRONT PANEL GCE-1 P MAIN(S) | R2; |  |  |  | M | Manufacture | DIP | 1 | PCS |  |
| 3 | B55.01109.M002 | 020.F0948.0029 | CONN CTR 15+14P SASM2130081TR SMD | R2_SA;HF_SA; | AMPHENOL | SASM2130081TR | Single |  | Purchase | SMT | 1 | PCS | CN1 |
| 3 | B55.01109.M002 | 062.40001.0521 | SW TACT 4P DTSM-62K-S-Q-T/R SMD | R2_SA;HF_SA; | DIPTRONICS | DTSM-62K-S-Q-T/R | Single |  | Purchase | SMT | 2 | PCS | SW3 SW4 |
| 3 | B55.01109.M002 | 071.09306.0A0I | IC SMBUS/I2C PCA9306DCTR SSOP8 | R2_SA;HF_SA; | TI | PCA9306DCTR | Multiple |  | Purchase | SMT | 2 | PCS | U12 U9 |
| A(Alternative to previous component) | B55.01109.M002 | 71.09306.00W | IC SMBUS/I2C PCA9306DP1 TSSOP 8P | R2_SA;HF_SA; | NXP | PCA9306DP1,125 |  |  | Purchase |  |  |  |  |
| 3 | B55.01109.M002 | 071.09555.000W | IC I/O EXPANDER TCA9555PWR TSSOP 24P | R2_SA;HF_SA; | TI | TCA9555PWR | Multiple |  | Purchase | SMT | 2 | PCS | U2 U4 |
| A | B55.01109.M002 | 71.09555.B0W | IC IO PCA9555PWRG4 TSSOP 24P | R2_SA;HF_SA; | TI | PCA9555PWRG4 |  |  | Purchase |  |  |  |  |
| 3 | B55.01109.M002 | 073.23157.0009 | IC A.S TS5A23157DGSR DGS 10P | R2_SA;HF_SA; | TI | TS5A23157DGSR | Multiple |  | Purchase | SMT | 2 | PCS | U1 U3 |
| A | B55.01109.M002 | 073.73157.0009 | IC A.S U7SB3157G-SM2-R MSOP 10P | R2_SA;HF_SA; | UTC | U7SB3157G-SM2-R |  |  | Purchase |  |  |  |  |
| 3 | B55.01109.M002 | 074.03422.0073 | IC CONT TPS3422EGDRYR USON 6P | R2_SA;HF_SA; | TI | TPS3422EGDRYR | Single |  | Purchase | SMT | 2 | PCS | U5 U6 |
| 3 | B55.01109.M002 | 075.006V1.0070 | IC DIODE ESD ESDALC6V1P5 SOT665 | R2_SA;HF_SA; | ST | ESDALC6V1P5 | Multiple |  | Purchase | SMT | 2 | PCS | D1 D2 |
| A | B55.01109.M002 | 075.3V3L4.0070 | IC DIODE ESD PESD3V3L4UW,115 SOT665 | R2_SA;HF_SA; | NEXPERIA | PESD3V3L4UW,115 |  |  | Purchase |  |  |  |  |
| 3 | B55.01109.M002 | 078.1022S.022L | CHIP CAP C 1000P 2KV K1206 X7R | R2_SA;HF_SA; | MURATA;YAGEO | GR431BR7LA102KW66L;CC1206KKX7RDBB102 | Multiple |  | Purchase | SMT | 2 | PCS | C16 C17 |
| 3 | B55.01109.M002 | 083.5V0X1.00AF | DIODE ESD PESD5V0X1UAB,115 SOD523 | R2_SA;HF_SA; | NEXPERIA | PESD5V0X1UAB,115 | Multiple |  | Purchase | SMT | 4 | PCS | D10 D7 D8 D9 |
| A | B55.01109.M002 | 083.PJSD5.00A0 | DIODE ESD PJSD05LCTS SOD-523 | R2_SA;HF_SA; | PANJIT | PJSD05LCTS |  |  | Purchase |  |  |  |  |
| A | B55.01109.M002 | 75.05125.070 | IC DIODE TVS AZ5125-01H.R7G SOD-523 | R2_SA;HF_SA;G_SA; | AMAZING | AZ5125-01H.R7G |  |  | Purchase |  |  |  |  |
| 3 | B55.01109.M002 | 086.2AT24.04R6 | THUMB SCREW SMT M3X0.5 L4.6 | R2_SA;HF_SA; | FIVETECH | FIVETECH | Single |  | Purchase | SMT | 1 | PCS | SCW1 |
| 3 | B55.01109.M002 | 63.12133.15L | CHIP RES 120 J 1/10W 0603(ROHS | R2_SA;HF_SA;G_SA; | TAI;RALEC;YAGEO;WALSIN | RM06JTN121;RTT03121JTP;RC0603JR-07120RL;WR06X121JTL | Multiple |  | Purchase | SMT | 2 | PCS | R25 R26 |
| 3 | B55.01109.M002 | 63.20134.1DL | CHIP RES 200 J 1/16W 0402 | R2_SA;HF_SA;G_SA; | TA-I ; RALEC ; CYNTEC ; YAGEO;WALSIN | RM04JTN201 ; RTT02201JTH ; RR0510S-201-JN ; RC0402JR-07200RL;WR04X201JTL | Multiple |  | Purchase | SMT | 2 | PCS | R15 R18 |
| 3 | B55.01109.M002 | 63.R0034.1DL | CHIP RES 0 J 1/16W 0402 | R2_SA;HF_SA;G_SA; | TAI;RALEC;CYNTEC;YAGEO;WALSIN | RM04JTN0;RTT02000JTH;RR0510X-000-XN;RC0402JR-070RL;WR04X000PTL | Multiple |  | Purchase | SMT | 14 | PCS | R12 R14 R16 R17 R19 R2 R20 R30 R31 R38 R39 R5 R7 R9 |
| 3 | B55.01109.M002 | 64.10015.6DL | CHIP RES 1K F 1/16W 0402 | R2_SA;HF_SA;G_SA; | TA-I;RALEC;CYNTEC;YAGEO;WALSIN | RM04FTN1001 ; RTT021001FTH ; RR0510S-102-FN ; RC0402FR-071KL;WR04X1001FTL | Multiple |  | Purchase | SMT | 2 | PCS | R49 R52 |
| 3 | B55.01109.M002 | 64.10025.6DL | CHIP RES 10K F 1/16W 0402 | R2_SA;HF_SA;G_SA; | TA-I;RALEC;CYNTEC;YAGEO;WALSIN | RM04FTN1002 ; RTT021002FTH ; RR0510S-103-FN ; RC0402FR-0710KL;WR04X1002FTL | Multiple |  | Purchase | SMT | 2 | PCS | R1 R8 |
| 3 | B55.01109.M002 | 64.10035.6DL | CHIP RES 100K F 1/16W 0402 | R2_SA;HF_SA;G_SA; | TA-I;RALEC;CYNTEC;YAGEO;WALSIN | RM04FTN1003 ; RTT021003FTH ; RR0510S-104-FN ; RC0402FR-07100KL;WR04X1003FTL | Multiple |  | Purchase | SMT | 2 | PCS | R59 R60 |
| 3 | B55.01109.M002 | 64.10045.6DL | CHIP RES 1M F 1/16W 0402 | R2_SA;HF_SA;G_SA; | TA-I;RALEC;CYNTEC;YAGEO;WALSIN | RM04FTN1004;RTT021004FTH;RR0510S-105-FN;RC0402FR-071ML;WR04X1004FTL | Multiple |  | Purchase | SMT | 2 | PCS | R45 R46 |
| 3 | B55.01109.M002 | 64.20025.6DL | CHIP RES 20K F 1/16W 0402 | R2_SA;HF_SA;G_SA; | TA-I;RALEC;CYNTEC;YAGEO;WALSIN | RM04FTN2002 ; RTT022002FTH ; RR0510S-203-FN ; RC0402FR-0720KL;WR04X2002FTL | Multiple |  | Purchase | SMT | 4 | PCS | R55 R56 R57 R58 |
| 3 | B55.01109.M002 | 64.47015.6DL | CHIP RES 4.7K F 1/16W 0402 | R2_SA;HF_SA;G_SA; | TA-I;RALEC;CYNTEC;YAGEO;WALSIN | RM04FTN4701;RTT024701FTH;RR0510S-472-FN;RC0402FR-074K7L;WR04X4701FTL | Multiple |  | Purchase | SMT | 20 | PCS | R29 R32 R33 R37 R40 R41 R48 R53 R61 R62 R63 R64 R68 R69 R72 R74 R77 R78 R79 R80 |
| 3 | B55.01109.M002 | 68.00084.A61 | CHIP BEAD BLM21PG300SN1D MURAT | R2_SA;HF_SA; | MURATA | BLM21PG300SN1D | Multiple |  | Purchase | SMT | 2 | PCS | L1 L3 |
| A | B55.01109.M002 | 68.00224.051 | CHIP BEAD MPZ2012S300AT TDK | R2_SA;HF_SA; | TDK | MPZ2012S300AT |  |  | Purchase |  |  |  |  |
| 3 | B55.01109.M002 | 73.01G08.L03 | IC CMOS SN74LVC1G08DCKR SC-70 | R2_SA;HF_SA;G_SA; | TI | SN74LVC1G08DCKR | Multiple |  | Purchase | SMT | 2 | PCS | U15 U16 |
| A | B55.01109.M002 | 073.7SZ08.000G | IC CMOS TC7SZ08FU,LJ(CT SSOP5-P-0.65A | R2_SA;HF_SA; | TOSHIBA | TC7SZ08FU,LJ(CT |  |  | Purchase |  |  |  |  |
| 3 | B55.01109.M002 | 73.07W74.0A7 | IC CMOS TC7WZ74FK SSOP8-P-0.50A | R2_SA;HF_SA; | TOSHIBA | TC7WZ74FK | Multiple |  | Purchase | SMT | 2 | PCS | U19 U20 |
| A | B55.01109.M002 | 73.01G74.0HF | IC CMOS SN74LVC1G74DCUR VSSOP-8P | R2_SA;HF_SA; | TI | SN74LVC1G74DCUR |  |  | Purchase |  |  |  |  |
| 3 | B55.01109.M002 | 73.1G126.DHG | IC CMOS SN74LVC1G126DCKR SC70 | R2_SA;HF_SA; | TI | SN74LVC1G126DCKR | Multiple |  | Purchase | SMT | 4 | PCS | U10 U11 U13 U14 |
| A | B55.01109.M002 | 073.7S126.000G | IC CMOS TC7SZ126FU,LJ(CT SSOP5-P-0.65A | R2_SA;HF_SA; | TOSHIBA | TC7SZ126FU,LJ(CT |  |  | Purchase |  |  |  |  |
| A | B55.01109.M002 | 73.7S126.AAH | IC CMOS NC7SZ126P5X SC70-5 | R2_SA;HF_SA; | FAIRCHILD | NC7SZ126P5X |  |  | Purchase |  |  |  |  |
| 3 | B55.01109.M002 | 74.00075.B79 | IC TEMP SENSOR TMP75AIDGKR MSOP 8P | R2_SA;HF_SA; | TI | TMP75AIDGKR | Multiple |  | Purchase | SMT | 2 | PCS | U7 U8 |
| A | B55.01109.M002 | 074.00752.M001 | IC TEMP SEN STTS75DS2F MSOP 8P(FIONA) | R2_SA;HF_SA; | ST | STTS75DS2F |  |  | Purchase |  |  |  |  |
| 3 | B55.01109.M002 | 75.005V0.A77 | IC DIODE ESD PESD5V0S1BL,315 SOD882 | R2_SA;HF_SA; | NEXPERIA | PESD5V0S1BL,315 | Single |  | Purchase | SMT | 2 | PCS | D3 D4 |
| 3 | B55.01109.M002 | 78.10421.2FL | CHIP CAP C 0.1U 16V K0402 X7R | R2_SA;HF_SA;G_SA; | DARFON;MURATA;PHYCOMP;SAMSUNG;TAIYO;WALSIN;YAGEO | C1005X7R104KET;GRM155R71C104KA88D;223878715649;CL05B104KO5NNNC;EMK105B7104KV-F;0402B104K160CT;CC0402KRX7R7BB104 | Multiple |  | Purchase | SMT | 20 | PCS | C1 C10 C12 C14 C15 C18 C19 C20 C21 C22 C23 C24 C25 C26 C27 C28 C29 C30 C5 C6 |
| 3 | B55.01109.M002 | 78.10521.2BL | CHIP CAP C 1U 16V K0603 X7R | R2_SA;HF_SA;G_SA; | KEMET;MURATA;TAIYO;TDK;YAGEO;WALSIN;SAMSUNG;DARFON | C0603C105K4RAC;GRM188R71C105KA12D;EMK107B7105KA-T;C1608X7R1C105KT;CC0603KRX7R7BB105;0603B105K160CT;CL10B105KO8NNNC;C1608X7R105KET | Multiple |  | Purchase | SMT | 8 | PCS | C11 C13 C2 C3 C4 C7 C8 C9 |
| 3 | B55.01109.M002 | B48.01138.0011 | PCB 16369-1 BRYCE CANYON FRONT PANE 4L G | R2_SA;HF_SA; | GCE | B48.01138.0011 | Multiple |  | Purchase | SMT | 1 | PCS |  |
| A | B55.01109.M002 | B48.01151.0011 | PCB 16369-1 BRYCE CANYON FRONT PANE 4L T | R2_SA;HF_SA; | TRIPOD | B48.01151.0011 |  |  | Purchase |  |  |  |  |
